# S9S_MB_2U (Grand Teton) — schematic netlist excerpt (pin names and nets, part order shuffled) for the footprints in the layout excerpt that follows; sources: Cadence DE-HDL packaged netlist, KiCad conversion of 03242023_DA0F0TMBIJ0_F0T_Motherboard_J_brd_V01_OCP.brd

PL26  Q_INDUCTOR4P_14  150NH IND  pkg L_TLM117513Q-151QL_11X7-5XA  page 287
  \1\  = SW_PVCCIN_CPU1_SW6
  \2\  = IND_P1_CPL6
  \3\  = IND_P1_CPL7
  \4\  = PVCCIN_CPU1

R3277  Q_RES  1K 1% EMPTY  pkg 0402LF  page 166 : A = P3V3_AUX ; B = FM_P2E_EQA0

(kicad_pcb
	(version 20260206)
	(generator "pcbnew")
	(generator_version "10.0")
	(general
		(thickness 1.6)
		(legacy_teardrops no)
	)
	(paper "A4")
	(title_block
		(title "03242023_DA0F0TMBIJ0_F0T_Motherboard_J_brd_V01_OCP.brd")
		(comment 1 "Grand Teton / footprints 3397-3398 of 6105")
	)
	(layers
		(0 "F.Cu" signal "TOP")
		(4 "In1.Cu" signal "GND")
		(6 "In2.Cu" signal "IN1")
		(8 "In3.Cu" signal "GND1")
		(10 "In4.Cu" signal "IN2")
		(12 "In5.Cu" signal "GND2")
		(14 "In6.Cu" signal "IN3")
		(16 "In7.Cu" signal "GND3")
		(18 "In8.Cu" signal "VCC")
		(20 "In9.Cu" signal "VCC1")
		(22 "In10.Cu" signal "GND4")
		(24 "In11.Cu" signal "IN4")
		(26 "In12.Cu" signal "GND5")
		(28 "In13.Cu" signal "IN5")
		(30 "In14.Cu" signal "GND6")
		(32 "In15.Cu" signal "IN6")
		(34 "In16.Cu" signal "GND7")
		(2 "B.Cu" signal "BOTTOM")
		(9 "F.Adhes" user "F.Adhesive")
		(11 "B.Adhes" user "B.Adhesive")
		(13 "F.Paste" user "Package Geometry/Pastemask Top")
		(15 "B.Paste" user "Package Geometry/Pastemask Bottom")
		(5 "F.SilkS" user "Ref Des/Silkscreen Top")
		(7 "B.SilkS" user "Ref Des/Silkscreen Bottom")
		(1 "F.Mask" user "Board Geometry/Soldermask Top")
		(3 "B.Mask" user "Board Geometry/Soldermask Bottom")
		(17 "Dwgs.User" user "User.Drawings")
		(19 "Cmts.User" user "User.Comments")
		(21 "Eco1.User" user "User.Eco1")
		(23 "Eco2.User" user "User.Eco2")
		(25 "Edge.Cuts" user "Board Geometry/Outline")
		(27 "Margin" user)
		(31 "F.CrtYd" user "Package Geometry/Place Bound Top")
		(29 "B.CrtYd" user "Package Geometry/Place Bound Bottom")
		(35 "F.Fab" user "Ref Des/Assembly Top")
		(33 "B.Fab" user "Ref Des/Assembly Bottom")
	)
	(footprint ""
		(layer "F.Cu")
		(at 22.225 -397.025876 -90)
		(property "Reference" "R3277"
			(at 0 0 270)
			(layer "F.SilkS")
			(hide yes)
			(effects
				(font
					(size 1.27 1.27)
				)
			)
		)
		(property "Value" ""
			(at 0 0 270)
			(layer "F.Fab")
			(effects
				(font
					(size 1.27 1.27)
				)
			)
		)
		(duplicate_pad_numbers_are_jumpers no)
		(fp_line
			(start -0.7874 0.4064)
			(end -0.7874 -0.4064)
			(stroke
				(width 0.1524)
				(type default)
			)
			(layer "F.SilkS")
		)
		(fp_line
			(start 0.7874 0.4064)
			(end -0.7874 0.4064)
			(stroke
				(width 0.1524)
				(type default)
			)
			(layer "F.SilkS")
		)
		(fp_line
			(start -0.7874 -0.4064)
			(end 0.7874 -0.4064)
			(stroke
				(width 0.1524)
				(type default)
			)
			(layer "F.SilkS")
		)
		(fp_line
			(start 0.7874 -0.4064)
			(end 0.7874 0.4064)
			(stroke
				(width 0.1524)
				(type default)
			)
			(layer "F.SilkS")
		)
		(fp_line
			(start -0.67945 0.3048)
			(end -0.67945 -0.305054)
			(stroke
				(width 0.1)
				(type default)
			)
			(layer "F.Fab")
		)
		(fp_line
			(start -0.12065 0.3048)
			(end -0.67945 0.3048)
			(stroke
				(width 0.1)
				(type default)
			)
			(layer "F.Fab")
		)
		(fp_line
			(start 0.120396 0.3048)
			(end 0.120396 0.2794)
			(stroke
				(width 0.1)
				(type default)
			)
			(layer "F.Fab")
		)
		(fp_line
			(start 0.67945 0.3048)
			(end 0.120396 0.3048)
			(stroke
				(width 0.1)
				(type default)
			)
			(layer "F.Fab")
		)
		(fp_line
			(start -0.12065 0.2794)
			(end -0.12065 0.3048)
			(stroke
				(width 0.1)
				(type default)
			)
			(layer "F.Fab")
		)
		(fp_line
			(start 0.120396 0.2794)
			(end -0.12065 0.2794)
			(stroke
				(width 0.1)
				(type default)
			)
			(layer "F.Fab")
		)
		(fp_line
			(start -0.12065 -0.2794)
			(end 0.12065 -0.2794)
			(stroke
				(width 0.1)
				(type default)
			)
			(layer "F.Fab")
		)
		(fp_line
			(start 0.12065 -0.2794)
			(end 0.12065 -0.3048)
			(stroke
				(width 0.1)
				(type default)
			)
			(layer "F.Fab")
		)
		(fp_line
			(start 0.12065 -0.3048)
			(end 0.67945 -0.3048)
			(stroke
				(width 0.1)
				(type default)
			)
			(layer "F.Fab")
		)
		(fp_line
			(start 0.67945 -0.3048)
			(end 0.67945 0.3048)
			(stroke
				(width 0.1)
				(type default)
			)
			(layer "F.Fab")
		)
		(fp_line
			(start -0.67945 -0.305054)
			(end -0.12065 -0.305054)
			(stroke
				(width 0.1)
				(type default)
			)
			(layer "F.Fab")
		)
		(fp_line
			(start -0.12065 -0.305054)
			(end -0.12065 -0.2794)
			(stroke
				(width 0.1)
				(type default)
			)
			(layer "F.Fab")
		)
		(pad "1" smd circle
			(at -0.40005 0 270)
			(size 0 0)
			(layers "F.Cu" "F.Mask" "F.Paste")
			(net "P3V3_AUX")
		)
		(pad "2" smd circle
			(at 0.40005 0 270)
			(size 0 0)
			(layers "F.Cu" "F.Mask" "F.Paste")
			(net "FM_P2E_EQA0")
		)
	)
	(footprint ""
		(layer "F.Cu")
		(at 88.8111 -327.768204)
		(property "Reference" "PL26"
			(at -3.844036 6.909054 0)
			(unlocked yes)
			(layer "F.SilkS")
			(effects
				(font
					(size 0.7874 0.5842)
					(thickness 0.1524)
				)
				(justify left)
			)
		)
		(property "Value" ""
			(at 0 0 0)
			(layer "F.Fab")
			(effects
				(font
					(size 1.27 1.27)
				)
			)
		)
		(duplicate_pad_numbers_are_jumpers no)
		(fp_line
			(start -3.750056 -5.500116)
			(end -2.393442 -5.500116)
			(stroke
				(width 0.1524)
				(type default)
			)
			(layer "F.SilkS")
		)
		(fp_line
			(start -3.750056 5.500116)
			(end -3.750056 -5.500116)
			(stroke
				(width 0.1524)
				(type default)
			)
			(layer "F.SilkS")
		)
		(fp_line
			(start -2.393442 5.500116)
			(end -3.750056 5.500116)
			(stroke
				(width 0.1524)
				(type default)
			)
			(layer "F.SilkS")
		)
		(fp_line
			(start 2.393442 5.500116)
			(end 3.750056 5.500116)
			(stroke
				(width 0.1524)
				(type default)
			)
			(layer "F.SilkS")
		)
		(fp_line
			(start 3.750056 -5.500116)
			(end 2.393442 -5.500116)
			(stroke
				(width 0.1524)
				(type default)
			)
			(layer "F.SilkS")
		)
		(fp_line
			(start 3.750056 5.500116)
			(end 3.750056 -5.500116)
			(stroke
				(width 0.1524)
				(type default)
			)
			(layer "F.SilkS")
		)
		(fp_poly
			(pts
				(xy -3.255772 -6.952996) (xy -2.896616 -5.875274) (xy -3.974338 -6.23443)
			)
			(stroke
				(width 0)
				(type default)
			)
			(fill yes)
			(layer "F.SilkS")
		)
		(fp_line
			(start -3.750056 -5.500116)
			(end -3.750056 5.500116)
			(stroke
				(width 0.1)
				(type default)
			)
			(layer "F.Fab")
		)
		(fp_line
			(start -3.750056 5.500116)
			(end 3.750056 5.500116)
			(stroke
				(width 0.1)
				(type default)
			)
			(layer "F.Fab")
		)
		(fp_line
			(start 3.750056 -5.500116)
			(end -3.750056 -5.500116)
			(stroke
				(width 0.1)
				(type default)
			)
			(layer "F.Fab")
		)
		(fp_line
			(start 3.750056 5.500116)
			(end 3.750056 -5.500116)
			(stroke
				(width 0.1)
				(type default)
			)
			(layer "F.Fab")
		)
		(fp_poly
			(pts
				(xy -4.9276 -4.757928) (xy -4.9276 -3.741928) (xy -3.9116 -4.249928)
			)
			(stroke
				(width 0)
				(type default)
			)
			(fill yes)
			(layer "F.Fab")
		)
		(pad "1" smd rect
			(at 0 -4.249928 270)
			(size 2.413 4.5212)
			(layers "F.Cu" "F.Mask" "F.Paste")
			(net "SW_PVCCIN_CPU1_SW6")
		)
		(pad "2" smd rect
			(at 0 -1.175004 270)
			(size 1.3716 4.5212)
			(layers "F.Cu" "F.Mask" "F.Paste")
			(net "IND_P1_CPL6")
		)
		(pad "3" smd rect
			(at 0 1.175004 270)
			(size 1.3716 4.5212)
			(layers "F.Cu" "F.Mask" "F.Paste")
			(net "IND_P1_CPL7")
		)
		(pad "4" smd rect
			(at 0 4.249928 270)
			(size 2.413 4.5212)
			(layers "F.Cu" "F.Mask" "F.Paste")
			(net "PVCCIN_CPU1")
		)
	)
)
